(kicad_pcb
	(version 20260206)
	(generator "pcbnew")
	(generator_version "10.0")
	(general
		(thickness 1.6)
		(legacy_teardrops no)
	)
	(paper "A4")
	(title_block
		(title "01162023_DA0F0TEBIF0_F0T_Expander_BD_F_brd_V02_OCP.brd")
		(comment 1 "Grand Teton / footprints 230-235 of 9728")
	)
	(layers
		(0 "F.Cu" signal "TOP")
		(4 "In1.Cu" signal "GND")
		(6 "In2.Cu" signal "VCC")
		(8 "In3.Cu" signal "VCC1")
		(10 "In4.Cu" signal "GND1")
		(12 "In5.Cu" signal "IN1")
		(14 "In6.Cu" signal "GND2")
		(16 "In7.Cu" signal "IN2")
		(18 "In8.Cu" signal "GND3")
		(20 "In9.Cu" signal "IN3")
		(22 "In10.Cu" signal "GND4")
		(24 "In11.Cu" signal "IN4")
		(26 "In12.Cu" signal "GND5")
		(28 "In13.Cu" signal "IN5")
		(30 "In14.Cu" signal "GND6")
		(32 "In15.Cu" signal "IN6")
		(34 "In16.Cu" signal "GND7")
		(2 "B.Cu" signal "BOTTOM")
		(9 "F.Adhes" user "F.Adhesive")
		(11 "B.Adhes" user "B.Adhesive")
		(13 "F.Paste" user "Package Geometry/Pastemask Top")
		(15 "B.Paste" user "Package Geometry/Pastemask Bottom")
		(5 "F.SilkS" user "Ref Des/Silkscreen Top")
		(7 "B.SilkS" user "Ref Des/Silkscreen Bottom")
		(1 "F.Mask" user "Board Geometry/Soldermask Top")
		(3 "B.Mask" user "Board Geometry/Soldermask Bottom")
		(17 "Dwgs.User" user "User.Drawings")
		(19 "Cmts.User" user "User.Comments")
		(21 "Eco1.User" user "User.Eco1")
		(23 "Eco2.User" user "User.Eco2")
		(25 "Edge.Cuts" user "Board Geometry/Outline")
		(27 "Margin" user)
		(31 "F.CrtYd" user "Package Geometry/Place Bound Top")
		(29 "B.CrtYd" user "Package Geometry/Place Bound Bottom")
		(35 "F.Fab" user "Ref Des/Assembly Top")
		(33 "B.Fab" user "Ref Des/Assembly Bottom")
	)
	(footprint ""
		(layer "F.Cu")
		(at 146.18208 -289.790632 180)
		(property "Reference" "C3223"
			(at 0 0 180)
			(layer "F.SilkS")
			(hide yes)
			(effects
				(font
					(size 1.27 1.27)
				)
			)
		)
		(property "Value" ""
			(at 0 0 180)
			(layer "F.Fab")
			(effects
				(font
					(size 1.27 1.27)
				)
			)
		)
		(duplicate_pad_numbers_are_jumpers no)
		(fp_line
			(start 1.2954 0.5842)
			(end -1.2954 0.5842)
			(stroke
				(width 0.1524)
				(type default)
			)
			(layer "F.SilkS")
		)
		(fp_line
			(start 1.2954 -0.5842)
			(end 1.2954 0.5842)
			(stroke
				(width 0.1524)
				(type default)
			)
			(layer "F.SilkS")
		)
		(fp_line
			(start -1.2954 0.5842)
			(end -1.2954 -0.5842)
			(stroke
				(width 0.1524)
				(type default)
			)
			(layer "F.SilkS")
		)
		(fp_line
			(start -1.2954 -0.5842)
			(end 1.2954 -0.5842)
			(stroke
				(width 0.1524)
				(type default)
			)
			(layer "F.SilkS")
		)
		(fp_line
			(start 1.1938 0.4064)
			(end 0.8636 0.4064)
			(stroke
				(width 0.1)
				(type default)
			)
			(layer "F.Fab")
		)
		(fp_line
			(start 1.1938 -0.4064)
			(end 1.1938 0.4064)
			(stroke
				(width 0.1)
				(type default)
			)
			(layer "F.Fab")
		)
		(fp_line
			(start 0.8636 0.4572)
			(end -0.8636 0.4572)
			(stroke
				(width 0.1)
				(type default)
			)
			(layer "F.Fab")
		)
		(fp_line
			(start 0.8636 0.4064)
			(end 0.8636 0.4572)
			(stroke
				(width 0.1)
				(type default)
			)
			(layer "F.Fab")
		)
		(fp_line
			(start 0.8636 -0.4064)
			(end 1.1938 -0.4064)
			(stroke
				(width 0.1)
				(type default)
			)
			(layer "F.Fab")
		)
		(fp_line
			(start 0.8636 -0.4572)
			(end 0.8636 -0.4064)
			(stroke
				(width 0.1)
				(type default)
			)
			(layer "F.Fab")
		)
		(fp_line
			(start -0.8636 0.4572)
			(end -0.8636 0.4064)
			(stroke
				(width 0.1)
				(type default)
			)
			(layer "F.Fab")
		)
		(fp_line
			(start -0.8636 0.4064)
			(end -1.1938 0.4064)
			(stroke
				(width 0.1)
				(type default)
			)
			(layer "F.Fab")
		)
		(fp_line
			(start -0.8636 -0.4064)
			(end -0.8636 -0.4572)
			(stroke
				(width 0.1)
				(type default)
			)
			(layer "F.Fab")
		)
		(fp_line
			(start -0.8636 -0.4572)
			(end 0.8636 -0.4572)
			(stroke
				(width 0.1)
				(type default)
			)
			(layer "F.Fab")
		)
		(fp_line
			(start -1.1938 0.4064)
			(end -1.1938 -0.4064)
			(stroke
				(width 0.1)
				(type default)
			)
			(layer "F.Fab")
		)
		(fp_line
			(start -1.1938 -0.4064)
			(end -0.8636 -0.4064)
			(stroke
				(width 0.1)
				(type default)
			)
			(layer "F.Fab")
		)
		(pad "1" smd rect
			(at -0.7366 0 90)
			(size 0.7112 0.8128)
			(layers "F.Cu" "F.Mask" "F.Paste")
			(net "PCEPLL4_VDDA18_PEX1_R")
		)
		(pad "2" smd rect
			(at 0.7366 0 90)
			(size 0.7112 0.8128)
			(layers "F.Cu" "F.Mask" "F.Paste")
			(net "GND")
		)
	)
	(footprint ""
		(layer "F.Cu")
		(at 267.519658 -206.897986 90)
		(property "Reference" "C3991"
			(at 0 0 90)
			(layer "F.SilkS")
			(hide yes)
			(effects
				(font
					(size 1.27 1.27)
				)
			)
		)
		(property "Value" ""
			(at 0 0 90)
			(layer "F.Fab")
			(effects
				(font
					(size 1.27 1.27)
				)
			)
		)
		(duplicate_pad_numbers_are_jumpers no)
		(fp_line
			(start 1.2954 -0.5842)
			(end 1.2954 0.5842)
			(stroke
				(width 0.1524)
				(type default)
			)
			(layer "F.SilkS")
		)
		(fp_line
			(start -1.2954 -0.5842)
			(end 1.2954 -0.5842)
			(stroke
				(width 0.1524)
				(type default)
			)
			(layer "F.SilkS")
		)
		(fp_line
			(start 1.2954 0.5842)
			(end -1.2954 0.5842)
			(stroke
				(width 0.1524)
				(type default)
			)
			(layer "F.SilkS")
		)
		(fp_line
			(start -1.2954 0.5842)
			(end -1.2954 -0.5842)
			(stroke
				(width 0.1524)
				(type default)
			)
			(layer "F.SilkS")
		)
		(fp_line
			(start 0.8636 -0.4572)
			(end 0.8636 -0.4064)
			(stroke
				(width 0.1)
				(type default)
			)
			(layer "F.Fab")
		)
		(fp_line
			(start -0.8636 -0.4572)
			(end 0.8636 -0.4572)
			(stroke
				(width 0.1)
				(type default)
			)
			(layer "F.Fab")
		)
		(fp_line
			(start 1.1938 -0.4064)
			(end 1.1938 0.4064)
			(stroke
				(width 0.1)
				(type default)
			)
			(layer "F.Fab")
		)
		(fp_line
			(start 0.8636 -0.4064)
			(end 1.1938 -0.4064)
			(stroke
				(width 0.1)
				(type default)
			)
			(layer "F.Fab")
		)
		(fp_line
			(start -0.8636 -0.4064)
			(end -0.8636 -0.4572)
			(stroke
				(width 0.1)
				(type default)
			)
			(layer "F.Fab")
		)
		(fp_line
			(start -1.1938 -0.4064)
			(end -0.8636 -0.4064)
			(stroke
				(width 0.1)
				(type default)
			)
			(layer "F.Fab")
		)
		(fp_line
			(start 1.1938 0.4064)
			(end 0.8636 0.4064)
			(stroke
				(width 0.1)
				(type default)
			)
			(layer "F.Fab")
		)
		(fp_line
			(start 0.8636 0.4064)
			(end 0.8636 0.4572)
			(stroke
				(width 0.1)
				(type default)
			)
			(layer "F.Fab")
		)
		(fp_line
			(start -0.8636 0.4064)
			(end -1.1938 0.4064)
			(stroke
				(width 0.1)
				(type default)
			)
			(layer "F.Fab")
		)
		(fp_line
			(start -1.1938 0.4064)
			(end -1.1938 -0.4064)
			(stroke
				(width 0.1)
				(type default)
			)
			(layer "F.Fab")
		)
		(fp_line
			(start 0.8636 0.4572)
			(end -0.8636 0.4572)
			(stroke
				(width 0.1)
				(type default)
			)
			(layer "F.Fab")
		)
		(fp_line
			(start -0.8636 0.4572)
			(end -0.8636 0.4064)
			(stroke
				(width 0.1)
				(type default)
			)
			(layer "F.Fab")
		)
		(pad "1" smd rect
			(at -0.7366 0)
			(size 0.7112 0.8128)
			(layers "F.Cu" "F.Mask" "F.Paste")
			(net "GND")
		)
		(pad "2" smd rect
			(at 0.7366 0)
			(size 0.7112 0.8128)
			(layers "F.Cu" "F.Mask" "F.Paste")
			(net "P3V3_AUX_JTAG")
		)
	)
	(footprint ""
		(layer "F.Cu")
		(at 288.915094 -59.546236 90)
		(property "Reference" "C2897"
			(at 0 0 90)
			(layer "F.SilkS")
			(hide yes)
			(effects
				(font
					(size 1.27 1.27)
				)
			)
		)
		(property "Value" ""
			(at 0 0 90)
			(layer "F.Fab")
			(effects
				(font
					(size 1.27 1.27)
				)
			)
		)
		(duplicate_pad_numbers_are_jumpers no)
		(fp_line
			(start 0.7874 -0.4064)
			(end 0.7874 0.4064)
			(stroke
				(width 0.1524)
				(type default)
			)
			(layer "F.SilkS")
		)
		(fp_line
			(start -0.7874 -0.4064)
			(end 0.7874 -0.4064)
			(stroke
				(width 0.1524)
				(type default)
			)
			(layer "F.SilkS")
		)
		(fp_line
			(start 0.7874 0.4064)
			(end -0.7874 0.4064)
			(stroke
				(width 0.1524)
				(type default)
			)
			(layer "F.SilkS")
		)
		(fp_line
			(start -0.7874 0.4064)
			(end -0.7874 -0.4064)
			(stroke
				(width 0.1524)
				(type default)
			)
			(layer "F.SilkS")
		)
		(fp_line
			(start -0.12065 -0.305054)
			(end -0.12065 -0.2794)
			(stroke
				(width 0.1)
				(type default)
			)
			(layer "F.Fab")
		)
		(fp_line
			(start -0.67945 -0.305054)
			(end -0.12065 -0.305054)
			(stroke
				(width 0.1)
				(type default)
			)
			(layer "F.Fab")
		)
		(fp_line
			(start 0.67945 -0.3048)
			(end 0.67945 0.3048)
			(stroke
				(width 0.1)
				(type default)
			)
			(layer "F.Fab")
		)
		(fp_line
			(start 0.12065 -0.3048)
			(end 0.67945 -0.3048)
			(stroke
				(width 0.1)
				(type default)
			)
			(layer "F.Fab")
		)
		(fp_line
			(start 0.12065 -0.2794)
			(end 0.12065 -0.3048)
			(stroke
				(width 0.1)
				(type default)
			)
			(layer "F.Fab")
		)
		(fp_line
			(start -0.12065 -0.2794)
			(end 0.12065 -0.2794)
			(stroke
				(width 0.1)
				(type default)
			)
			(layer "F.Fab")
		)
		(fp_line
			(start 0.120396 0.2794)
			(end -0.12065 0.2794)
			(stroke
				(width 0.1)
				(type default)
			)
			(layer "F.Fab")
		)
		(fp_line
			(start -0.12065 0.2794)
			(end -0.12065 0.3048)
			(stroke
				(width 0.1)
				(type default)
			)
			(layer "F.Fab")
		)
		(fp_line
			(start 0.67945 0.3048)
			(end 0.120396 0.3048)
			(stroke
				(width 0.1)
				(type default)
			)
			(layer "F.Fab")
		)
		(fp_line
			(start 0.120396 0.3048)
			(end 0.120396 0.2794)
			(stroke
				(width 0.1)
				(type default)
			)
			(layer "F.Fab")
		)
		(fp_line
			(start -0.12065 0.3048)
			(end -0.67945 0.3048)
			(stroke
				(width 0.1)
				(type default)
			)
			(layer "F.Fab")
		)
		(fp_line
			(start -0.67945 0.3048)
			(end -0.67945 -0.305054)
			(stroke
				(width 0.1)
				(type default)
			)
			(layer "F.Fab")
		)
		(pad "1" smd circle
			(at -0.40005 0 90)
			(size 0 0)
			(layers "F.Cu" "F.Mask" "F.Paste")
			(net "SSD10_AUX_P3V3_EN_R")
		)
		(pad "2" smd circle
			(at 0.40005 0 90)
			(size 0 0)
			(layers "F.Cu" "F.Mask" "F.Paste")
			(net "GND")
		)
	)
	(footprint ""
		(layer "F.Cu")
		(at 291.194998 -104.830372 180)
		(property "Reference" "R275"
			(at 0 0 180)
			(layer "F.SilkS")
			(hide yes)
			(effects
				(font
					(size 1.27 1.27)
				)
			)
		)
		(property "Value" ""
			(at 0 0 180)
			(layer "F.Fab")
			(effects
				(font
					(size 1.27 1.27)
				)
			)
		)
		(duplicate_pad_numbers_are_jumpers no)
		(fp_line
			(start 0.7874 0.4064)
			(end -0.7874 0.4064)
			(stroke
				(width 0.1524)
				(type default)
			)
			(layer "F.SilkS")
		)
		(fp_line
			(start 0.7874 -0.4064)
			(end 0.7874 0.4064)
			(stroke
				(width 0.1524)
				(type default)
			)
			(layer "F.SilkS")
		)
		(fp_line
			(start -0.7874 0.4064)
			(end -0.7874 -0.4064)
			(stroke
				(width 0.1524)
				(type default)
			)
			(layer "F.SilkS")
		)
		(fp_line
			(start -0.7874 -0.4064)
			(end 0.7874 -0.4064)
			(stroke
				(width 0.1524)
				(type default)
			)
			(layer "F.SilkS")
		)
		(fp_line
			(start 0.67945 0.3048)
			(end 0.120396 0.3048)
			(stroke
				(width 0.1)
				(type default)
			)
			(layer "F.Fab")
		)
		(fp_line
			(start 0.67945 -0.3048)
			(end 0.67945 0.3048)
			(stroke
				(width 0.1)
				(type default)
			)
			(layer "F.Fab")
		)
		(fp_line
			(start 0.12065 -0.2794)
			(end 0.12065 -0.3048)
			(stroke
				(width 0.1)
				(type default)
			)
			(layer "F.Fab")
		)
		(fp_line
			(start 0.12065 -0.3048)
			(end 0.67945 -0.3048)
			(stroke
				(width 0.1)
				(type default)
			)
			(layer "F.Fab")
		)
		(fp_line
			(start 0.120396 0.3048)
			(end 0.120396 0.2794)
			(stroke
				(width 0.1)
				(type default)
			)
			(layer "F.Fab")
		)
		(fp_line
			(start 0.120396 0.2794)
			(end -0.12065 0.2794)
			(stroke
				(width 0.1)
				(type default)
			)
			(layer "F.Fab")
		)
		(fp_line
			(start -0.12065 0.3048)
			(end -0.67945 0.3048)
			(stroke
				(width 0.1)
				(type default)
			)
			(layer "F.Fab")
		)
		(fp_line
			(start -0.12065 0.2794)
			(end -0.12065 0.3048)
			(stroke
				(width 0.1)
				(type default)
			)
			(layer "F.Fab")
		)
		(fp_line
			(start -0.12065 -0.2794)
			(end 0.12065 -0.2794)
			(stroke
				(width 0.1)
				(type default)
			)
			(layer "F.Fab")
		)
		(fp_line
			(start -0.12065 -0.305054)
			(end -0.12065 -0.2794)
			(stroke
				(width 0.1)
				(type default)
			)
			(layer "F.Fab")
		)
		(fp_line
			(start -0.67945 0.3048)
			(end -0.67945 -0.305054)
			(stroke
				(width 0.1)
				(type default)
			)
			(layer "F.Fab")
		)
		(fp_line
			(start -0.67945 -0.305054)
			(end -0.12065 -0.305054)
			(stroke
				(width 0.1)
				(type default)
			)
			(layer "F.Fab")
		)
		(pad "1" smd circle
			(at -0.40005 0 180)
			(size 0 0)
			(layers "F.Cu" "F.Mask" "F.Paste")
			(net "CLK_50M_NIC5_RBT_REF")
		)
		(pad "2" smd circle
			(at 0.40005 0 180)
			(size 0 0)
			(layers "F.Cu" "F.Mask" "F.Paste")
			(net "GND")
		)
	)
	(footprint ""
		(layer "F.Cu")
		(at 365.506 -211.963 180)
		(property "Reference" "R4623"
			(at 0 0 180)
			(layer "F.SilkS")
			(hide yes)
			(effects
				(font
					(size 1.27 1.27)
				)
			)
		)
		(property "Value" ""
			(at 0 0 180)
			(layer "F.Fab")
			(effects
				(font
					(size 1.27 1.27)
				)
			)
		)
		(duplicate_pad_numbers_are_jumpers no)
		(fp_line
			(start 0.7874 0.4064)
			(end -0.7874 0.4064)
			(stroke
				(width 0.1524)
				(type default)
			)
			(layer "F.SilkS")
		)
		(fp_line
			(start 0.7874 -0.4064)
			(end 0.7874 0.4064)
			(stroke
				(width 0.1524)
				(type default)
			)
			(layer "F.SilkS")
		)
		(fp_line
			(start -0.7874 0.4064)
			(end -0.7874 -0.4064)
			(stroke
				(width 0.1524)
				(type default)
			)
			(layer "F.SilkS")
		)
		(fp_line
			(start -0.7874 -0.4064)
			(end 0.7874 -0.4064)
			(stroke
				(width 0.1524)
				(type default)
			)
			(layer "F.SilkS")
		)
		(fp_line
			(start 0.67945 0.3048)
			(end 0.120396 0.3048)
			(stroke
				(width 0.1)
				(type default)
			)
			(layer "F.Fab")
		)
		(fp_line
			(start 0.67945 -0.3048)
			(end 0.67945 0.3048)
			(stroke
				(width 0.1)
				(type default)
			)
			(layer "F.Fab")
		)
		(fp_line
			(start 0.12065 -0.2794)
			(end 0.12065 -0.3048)
			(stroke
				(width 0.1)
				(type default)
			)
			(layer "F.Fab")
		)
		(fp_line
			(start 0.12065 -0.3048)
			(end 0.67945 -0.3048)
			(stroke
				(width 0.1)
				(type default)
			)
			(layer "F.Fab")
		)
		(fp_line
			(start 0.120396 0.3048)
			(end 0.120396 0.2794)
			(stroke
				(width 0.1)
				(type default)
			)
			(layer "F.Fab")
		)
		(fp_line
			(start 0.120396 0.2794)
			(end -0.12065 0.2794)
			(stroke
				(width 0.1)
				(type default)
			)
			(layer "F.Fab")
		)
		(fp_line
			(start -0.12065 0.3048)
			(end -0.67945 0.3048)
			(stroke
				(width 0.1)
				(type default)
			)
			(layer "F.Fab")
		)
		(fp_line
			(start -0.12065 0.2794)
			(end -0.12065 0.3048)
			(stroke
				(width 0.1)
				(type default)
			)
			(layer "F.Fab")
		)
		(fp_line
			(start -0.12065 -0.2794)
			(end 0.12065 -0.2794)
			(stroke
				(width 0.1)
				(type default)
			)
			(layer "F.Fab")
		)
		(fp_line
			(start -0.12065 -0.305054)
			(end -0.12065 -0.2794)
			(stroke
				(width 0.1)
				(type default)
			)
			(layer "F.Fab")
		)
		(fp_line
			(start -0.67945 0.3048)
			(end -0.67945 -0.305054)
			(stroke
				(width 0.1)
				(type default)
			)
			(layer "F.Fab")
		)
		(fp_line
			(start -0.67945 -0.305054)
			(end -0.12065 -0.305054)
			(stroke
				(width 0.1)
				(type default)
			)
			(layer "F.Fab")
		)
		(pad "1" smd circle
			(at -0.40005 0 180)
			(size 0 0)
			(layers "F.Cu" "F.Mask" "F.Paste")
			(net "PRSNT_SSD0_FPGA_PCA9555_N")
		)
		(pad "2" smd circle
			(at 0.40005 0 180)
			(size 0 0)
			(layers "F.Cu" "F.Mask" "F.Paste")
			(net "PRSNT_SSD0_FPGA_R_N")
		)
	)
	(footprint ""
		(layer "F.Cu")
		(at 366.955578 -89.499694 180)
		(property "Reference" "R1630"
			(at 0 0 180)
			(layer "F.SilkS")
			(hide yes)
			(effects
				(font
					(size 1.27 1.27)
				)
			)
		)
		(property "Value" ""
			(at 0 0 180)
			(layer "F.Fab")
			(effects
				(font
					(size 1.27 1.27)
				)
			)
		)
		(duplicate_pad_numbers_are_jumpers no)
		(fp_line
			(start 0.7874 0.4064)
			(end -0.7874 0.4064)
			(stroke
				(width 0.1524)
				(type default)
			)
			(layer "F.SilkS")
		)
		(fp_line
			(start 0.7874 -0.4064)
			(end 0.7874 0.4064)
			(stroke
				(width 0.1524)
				(type default)
			)
			(layer "F.SilkS")
		)
		(fp_line
			(start -0.7874 0.4064)
			(end -0.7874 -0.4064)
			(stroke
				(width 0.1524)
				(type default)
			)
			(layer "F.SilkS")
		)
		(fp_line
			(start -0.7874 -0.4064)
			(end 0.7874 -0.4064)
			(stroke
				(width 0.1524)
				(type default)
			)
			(layer "F.SilkS")
		)
		(fp_line
			(start 0.67945 0.3048)
			(end 0.120396 0.3048)
			(stroke
				(width 0.1)
				(type default)
			)
			(layer "F.Fab")
		)
		(fp_line
			(start 0.67945 -0.3048)
			(end 0.67945 0.3048)
			(stroke
				(width 0.1)
				(type default)
			)
			(layer "F.Fab")
		)
		(fp_line
			(start 0.12065 -0.2794)
			(end 0.12065 -0.3048)
			(stroke
				(width 0.1)
				(type default)
			)
			(layer "F.Fab")
		)
		(fp_line
			(start 0.12065 -0.3048)
			(end 0.67945 -0.3048)
			(stroke
				(width 0.1)
				(type default)
			)
			(layer "F.Fab")
		)
		(fp_line
			(start 0.120396 0.3048)
			(end 0.120396 0.2794)
			(stroke
				(width 0.1)
				(type default)
			)
			(layer "F.Fab")
		)
		(fp_line
			(start 0.120396 0.2794)
			(end -0.12065 0.2794)
			(stroke
				(width 0.1)
				(type default)
			)
			(layer "F.Fab")
		)
		(fp_line
			(start -0.12065 0.3048)
			(end -0.67945 0.3048)
			(stroke
				(width 0.1)
				(type default)
			)
			(layer "F.Fab")
		)
		(fp_line
			(start -0.12065 0.2794)
			(end -0.12065 0.3048)
			(stroke
				(width 0.1)
				(type default)
			)
			(layer "F.Fab")
		)
		(fp_line
			(start -0.12065 -0.2794)
			(end 0.12065 -0.2794)
			(stroke
				(width 0.1)
				(type default)
			)
			(layer "F.Fab")
		)
		(fp_line
			(start -0.12065 -0.305054)
			(end -0.12065 -0.2794)
			(stroke
				(width 0.1)
				(type default)
			)
			(layer "F.Fab")
		)
		(fp_line
			(start -0.67945 0.3048)
			(end -0.67945 -0.305054)
			(stroke
				(width 0.1)
				(type default)
			)
			(layer "F.Fab")
		)
		(fp_line
			(start -0.67945 -0.305054)
			(end -0.12065 -0.305054)
			(stroke
				(width 0.1)
				(type default)
			)
			(layer "F.Fab")
		)
		(pad "1" smd circle
			(at -0.40005 0 180)
			(size 0 0)
			(layers "F.Cu" "F.Mask" "F.Paste")
			(net "SMB_BIC_I2C9_MUX1_SSD15_R_SCL")
		)
		(pad "2" smd circle
			(at 0.40005 0 180)
			(size 0 0)
			(layers "F.Cu" "F.Mask" "F.Paste")
			(net "SMB_BIC_I2C9_MUX1_SSD15_SCL")
		)
	)
)
